(kicad_pcb
	(version 20260206)
	(generator "pcbnew")
	(generator_version "10.0")
	(general
		(thickness 1.6)
		(legacy_teardrops no)
	)
	(paper "A4")
	(title_block
		(title "03242023_DA0F0TMBIJ0_F0T_Motherboard_J_brd_V01_OCP.brd")
		(comment 1 "Grand Teton / footprint 3553 of 6105 (J6), pads 225-291 of 291")
	)
	(layers
		(0 "F.Cu" signal "TOP")
		(4 "In1.Cu" signal "GND")
		(6 "In2.Cu" signal "IN1")
		(8 "In3.Cu" signal "GND1")
		(10 "In4.Cu" signal "IN2")
		(12 "In5.Cu" signal "GND2")
		(14 "In6.Cu" signal "IN3")
		(16 "In7.Cu" signal "GND3")
		(18 "In8.Cu" signal "VCC")
		(20 "In9.Cu" signal "VCC1")
		(22 "In10.Cu" signal "GND4")
		(24 "In11.Cu" signal "IN4")
		(26 "In12.Cu" signal "GND5")
		(28 "In13.Cu" signal "IN5")
		(30 "In14.Cu" signal "GND6")
		(32 "In15.Cu" signal "IN6")
		(34 "In16.Cu" signal "GND7")
		(2 "B.Cu" signal "BOTTOM")
		(9 "F.Adhes" user "F.Adhesive")
		(11 "B.Adhes" user "B.Adhesive")
		(13 "F.Paste" user "Package Geometry/Pastemask Top")
		(15 "B.Paste" user "Package Geometry/Pastemask Bottom")
		(5 "F.SilkS" user "Ref Des/Silkscreen Top")
		(7 "B.SilkS" user "Ref Des/Silkscreen Bottom")
		(1 "F.Mask" user "Board Geometry/Soldermask Top")
		(3 "B.Mask" user "Board Geometry/Soldermask Bottom")
		(17 "Dwgs.User" user "User.Drawings")
		(19 "Cmts.User" user "User.Comments")
		(21 "Eco1.User" user "User.Eco1")
		(23 "Eco2.User" user "User.Eco2")
		(25 "Edge.Cuts" user "Board Geometry/Outline")
		(27 "Margin" user)
		(31 "F.CrtYd" user "Package Geometry/Place Bound Top")
		(29 "B.CrtYd" user "Package Geometry/Place Bound Bottom")
		(35 "F.Fab" user "Ref Des/Assembly Top")
		(33 "B.Fab" user "Ref Des/Assembly Bottom")
	)
	(footprint ""
		(layer "F.Cu")
		(at 280.761948 -258.091686)
		(property "Reference" "J6"
			(at -3.683 -81.702148 0)
			(unlocked yes)
			(layer "F.SilkS")
			(effects
				(font
					(size 0.7874 0.5842)
					(thickness 0.1524)
				)
				(justify left)
			)
		)
		(property "Value" ""
			(at 0 0 0)
			(layer "F.Fab")
			(effects
				(font
					(size 1.27 1.27)
				)
			)
		)
		(duplicate_pad_numbers_are_jumpers no)
		(pad "225" smd rect
			(at 2.050034 9.774936 270)
			(size 0.519938 1.4986)
			(layers "F.Cu" "F.Mask" "F.Paste")
			(net "M_C_CPU0_SB_CA<5>")
		)
		(pad "226" smd rect
			(at 2.050034 10.625074 270)
			(size 0.519938 1.4986)
			(layers "F.Cu" "F.Mask" "F.Paste")
			(net "GND")
		)
		(pad "227" smd rect
			(at 2.050034 11.474958 270)
			(size 0.519938 1.4986)
			(layers "F.Cu" "F.Mask" "F.Paste")
			(net "M_C_CPU0_SB_PAR")
		)
		(pad "228" smd rect
			(at 2.050034 12.325096 270)
			(size 0.519938 1.4986)
			(layers "F.Cu" "F.Mask" "F.Paste")
			(net "GND")
		)
		(pad "229" smd rect
			(at 2.050034 13.17498 270)
			(size 0.519938 1.4986)
			(layers "F.Cu" "F.Mask" "F.Paste")
			(net "M_C_CPU0_SB_CS_N<3>")
		)
		(pad "230" smd rect
			(at 2.050034 14.025118 270)
			(size 0.519938 1.4986)
			(layers "F.Cu" "F.Mask" "F.Paste")
			(net "GND")
		)
		(pad "231" smd rect
			(at 2.050034 14.875002 270)
			(size 0.519938 1.4986)
			(layers "F.Cu" "F.Mask" "F.Paste")
			(net "TP_CHC_CPU0_DIMM2_FRU_5")
		)
		(pad "232" smd rect
			(at 2.050034 15.724886 270)
			(size 0.519938 1.4986)
			(layers "F.Cu" "F.Mask" "F.Paste")
			(net "TP_CHC_CPU0_DIMM2_FRU_6")
		)
		(pad "233" smd rect
			(at 2.050034 16.575024 270)
			(size 0.519938 1.4986)
			(layers "F.Cu" "F.Mask" "F.Paste")
			(net "GND")
		)
		(pad "234" smd rect
			(at 2.050034 17.424908 270)
			(size 0.519938 1.4986)
			(layers "F.Cu" "F.Mask" "F.Paste")
			(net "M_C_CPU0_SB_CB<6>")
		)
		(pad "235" smd rect
			(at 2.050034 18.275046 270)
			(size 0.519938 1.4986)
			(layers "F.Cu" "F.Mask" "F.Paste")
			(net "GND")
		)
		(pad "236" smd rect
			(at 2.050034 19.12493 270)
			(size 0.519938 1.4986)
			(layers "F.Cu" "F.Mask" "F.Paste")
			(net "M_C_CPU0_SB_CB<7>")
		)
		(pad "237" smd rect
			(at 2.050034 19.975068 270)
			(size 0.519938 1.4986)
			(layers "F.Cu" "F.Mask" "F.Paste")
			(net "GND")
		)
		(pad "238" smd rect
			(at 2.050034 20.824952 270)
			(size 0.519938 1.4986)
			(layers "F.Cu" "F.Mask" "F.Paste")
			(net "M_C_CPU0_SB_DQS_DN<4>")
		)
		(pad "239" smd rect
			(at 2.050034 21.67509 270)
			(size 0.519938 1.4986)
			(layers "F.Cu" "F.Mask" "F.Paste")
			(net "M_C_CPU0_SB_DQS_DP<4>")
		)
		(pad "240" smd rect
			(at 2.050034 22.524974 270)
			(size 0.519938 1.4986)
			(layers "F.Cu" "F.Mask" "F.Paste")
			(net "GND")
		)
		(pad "241" smd rect
			(at 2.050034 23.375112 270)
			(size 0.519938 1.4986)
			(layers "F.Cu" "F.Mask" "F.Paste")
			(net "M_C_CPU0_SB_CB<2>")
		)
		(pad "242" smd rect
			(at 2.050034 24.224996 270)
			(size 0.519938 1.4986)
			(layers "F.Cu" "F.Mask" "F.Paste")
			(net "GND")
		)
		(pad "243" smd rect
			(at 2.050034 25.07488 270)
			(size 0.519938 1.4986)
			(layers "F.Cu" "F.Mask" "F.Paste")
			(net "M_C_CPU0_SB_CB<3>")
		)
		(pad "244" smd rect
			(at 2.050034 25.925018 270)
			(size 0.519938 1.4986)
			(layers "F.Cu" "F.Mask" "F.Paste")
			(net "GND")
		)
		(pad "245" smd rect
			(at 2.050034 26.774902 270)
			(size 0.519938 1.4986)
			(layers "F.Cu" "F.Mask" "F.Paste")
			(net "M_C_CPU0_SB_DQ<2>")
		)
		(pad "246" smd rect
			(at 2.050034 27.62504 270)
			(size 0.519938 1.4986)
			(layers "F.Cu" "F.Mask" "F.Paste")
			(net "GND")
		)
		(pad "247" smd rect
			(at 2.050034 28.474924 270)
			(size 0.519938 1.4986)
			(layers "F.Cu" "F.Mask" "F.Paste")
			(net "M_C_CPU0_SB_DQ<3>")
		)
		(pad "248" smd rect
			(at 2.050034 29.325062 270)
			(size 0.519938 1.4986)
			(layers "F.Cu" "F.Mask" "F.Paste")
			(net "GND")
		)
		(pad "249" smd rect
			(at 2.050034 30.174946 270)
			(size 0.519938 1.4986)
			(layers "F.Cu" "F.Mask" "F.Paste")
			(net "M_C_CPU0_SB_DQS_DN<5>")
		)
		(pad "250" smd rect
			(at 2.050034 31.025084 270)
			(size 0.519938 1.4986)
			(layers "F.Cu" "F.Mask" "F.Paste")
			(net "M_C_CPU0_SB_DQS_DP<5>")
		)
		(pad "251" smd rect
			(at 2.050034 31.874968 270)
			(size 0.519938 1.4986)
			(layers "F.Cu" "F.Mask" "F.Paste")
			(net "GND")
		)
		(pad "252" smd rect
			(at 2.050034 32.725106 270)
			(size 0.519938 1.4986)
			(layers "F.Cu" "F.Mask" "F.Paste")
			(net "M_C_CPU0_SB_DQ<6>")
		)
		(pad "253" smd rect
			(at 2.050034 33.57499 270)
			(size 0.519938 1.4986)
			(layers "F.Cu" "F.Mask" "F.Paste")
			(net "GND")
		)
		(pad "254" smd rect
			(at 2.050034 34.425128 270)
			(size 0.519938 1.4986)
			(layers "F.Cu" "F.Mask" "F.Paste")
			(net "M_C_CPU0_SB_DQ<7>")
		)
		(pad "255" smd rect
			(at 2.050034 35.275012 270)
			(size 0.519938 1.4986)
			(layers "F.Cu" "F.Mask" "F.Paste")
			(net "GND")
		)
		(pad "256" smd rect
			(at 2.050034 36.124896 270)
			(size 0.519938 1.4986)
			(layers "F.Cu" "F.Mask" "F.Paste")
			(net "M_C_CPU0_SB_DQ<10>")
		)
		(pad "257" smd rect
			(at 2.050034 36.975034 270)
			(size 0.519938 1.4986)
			(layers "F.Cu" "F.Mask" "F.Paste")
			(net "GND")
		)
		(pad "258" smd rect
			(at 2.050034 37.824918 270)
			(size 0.519938 1.4986)
			(layers "F.Cu" "F.Mask" "F.Paste")
			(net "M_C_CPU0_SB_DQ<11>")
		)
		(pad "259" smd rect
			(at 2.050034 38.675056 270)
			(size 0.519938 1.4986)
			(layers "F.Cu" "F.Mask" "F.Paste")
			(net "GND")
		)
		(pad "260" smd rect
			(at 2.050034 39.52494 270)
			(size 0.519938 1.4986)
			(layers "F.Cu" "F.Mask" "F.Paste")
			(net "M_C_CPU0_SB_DQS_DN<6>")
		)
		(pad "261" smd rect
			(at 2.050034 40.375078 270)
			(size 0.519938 1.4986)
			(layers "F.Cu" "F.Mask" "F.Paste")
			(net "M_C_CPU0_SB_DQS_DP<6>")
		)
		(pad "262" smd rect
			(at 2.050034 41.224962 270)
			(size 0.519938 1.4986)
			(layers "F.Cu" "F.Mask" "F.Paste")
			(net "GND")
		)
		(pad "263" smd rect
			(at 2.050034 42.0751 270)
			(size 0.519938 1.4986)
			(layers "F.Cu" "F.Mask" "F.Paste")
			(net "M_C_CPU0_SB_DQ<14>")
		)
		(pad "264" smd rect
			(at 2.050034 42.924984 270)
			(size 0.519938 1.4986)
			(layers "F.Cu" "F.Mask" "F.Paste")
			(net "GND")
		)
		(pad "265" smd rect
			(at 2.050034 43.775122 270)
			(size 0.519938 1.4986)
			(layers "F.Cu" "F.Mask" "F.Paste")
			(net "M_C_CPU0_SB_DQ<15>")
		)
		(pad "266" smd rect
			(at 2.050034 44.625006 270)
			(size 0.519938 1.4986)
			(layers "F.Cu" "F.Mask" "F.Paste")
			(net "GND")
		)
		(pad "267" smd rect
			(at 2.050034 45.47489 270)
			(size 0.519938 1.4986)
			(layers "F.Cu" "F.Mask" "F.Paste")
			(net "M_C_CPU0_SB_DQ<18>")
		)
		(pad "268" smd rect
			(at 2.050034 46.325028 270)
			(size 0.519938 1.4986)
			(layers "F.Cu" "F.Mask" "F.Paste")
			(net "GND")
		)
		(pad "269" smd rect
			(at 2.050034 47.174912 270)
			(size 0.519938 1.4986)
			(layers "F.Cu" "F.Mask" "F.Paste")
			(net "M_C_CPU0_SB_DQ<19>")
		)
		(pad "270" smd rect
			(at 2.050034 48.02505 270)
			(size 0.519938 1.4986)
			(layers "F.Cu" "F.Mask" "F.Paste")
			(net "GND")
		)
		(pad "271" smd rect
			(at 2.050034 48.874934 270)
			(size 0.519938 1.4986)
			(layers "F.Cu" "F.Mask" "F.Paste")
			(net "M_C_CPU0_SB_DQS_DN<7>")
		)
		(pad "272" smd rect
			(at 2.050034 49.725072 270)
			(size 0.519938 1.4986)
			(layers "F.Cu" "F.Mask" "F.Paste")
			(net "M_C_CPU0_SB_DQS_DP<7>")
		)
		(pad "273" smd rect
			(at 2.050034 50.574956 270)
			(size 0.519938 1.4986)
			(layers "F.Cu" "F.Mask" "F.Paste")
			(net "GND")
		)
		(pad "274" smd rect
			(at 2.050034 51.425094 270)
			(size 0.519938 1.4986)
			(layers "F.Cu" "F.Mask" "F.Paste")
			(net "M_C_CPU0_SB_DQ<22>")
		)
		(pad "275" smd rect
			(at 2.050034 52.274978 270)
			(size 0.519938 1.4986)
			(layers "F.Cu" "F.Mask" "F.Paste")
			(net "GND")
		)
		(pad "276" smd rect
			(at 2.050034 53.125116 270)
			(size 0.519938 1.4986)
			(layers "F.Cu" "F.Mask" "F.Paste")
			(net "M_C_CPU0_SB_DQ<23>")
		)
		(pad "277" smd rect
			(at 2.050034 53.975 270)
			(size 0.519938 1.4986)
			(layers "F.Cu" "F.Mask" "F.Paste")
			(net "GND")
		)
		(pad "278" smd rect
			(at 2.050034 54.824884 270)
			(size 0.519938 1.4986)
			(layers "F.Cu" "F.Mask" "F.Paste")
			(net "M_C_CPU0_SB_DQ<26>")
		)
		(pad "279" smd rect
			(at 2.050034 55.675022 270)
			(size 0.519938 1.4986)
			(layers "F.Cu" "F.Mask" "F.Paste")
			(net "GND")
		)
		(pad "280" smd rect
			(at 2.050034 56.524906 270)
			(size 0.519938 1.4986)
			(layers "F.Cu" "F.Mask" "F.Paste")
			(net "M_C_CPU0_SB_DQ<27>")
		)
		(pad "281" smd rect
			(at 2.050034 57.375044 270)
			(size 0.519938 1.4986)
			(layers "F.Cu" "F.Mask" "F.Paste")
			(net "GND")
		)
		(pad "282" smd rect
			(at 2.050034 58.224928 270)
			(size 0.519938 1.4986)
			(layers "F.Cu" "F.Mask" "F.Paste")
			(net "M_C_CPU0_SB_DQS_DN<8>")
		)
		(pad "283" smd rect
			(at 2.050034 59.075066 270)
			(size 0.519938 1.4986)
			(layers "F.Cu" "F.Mask" "F.Paste")
			(net "M_C_CPU0_SB_DQS_DP<8>")
		)
		(pad "284" smd rect
			(at 2.050034 59.92495 270)
			(size 0.519938 1.4986)
			(layers "F.Cu" "F.Mask" "F.Paste")
			(net "GND")
		)
		(pad "285" smd rect
			(at 2.050034 60.775088 270)
			(size 0.519938 1.4986)
			(layers "F.Cu" "F.Mask" "F.Paste")
			(net "M_C_CPU0_SB_DQ<30>")
		)
		(pad "286" smd rect
			(at 2.050034 61.624972 270)
			(size 0.519938 1.4986)
			(layers "F.Cu" "F.Mask" "F.Paste")
			(net "GND")
		)
		(pad "287" smd rect
			(at 2.050034 62.47511 270)
			(size 0.519938 1.4986)
			(layers "F.Cu" "F.Mask" "F.Paste")
			(net "M_C_CPU0_SB_DQ<31>")
		)
		(pad "288" smd rect
			(at 2.050034 63.324994 270)
			(size 0.519938 1.4986)
			(layers "F.Cu" "F.Mask" "F.Paste")
			(net "GND")
		)
		(pad "G1" thru_hole oval
			(at 0 -68.97497)
			(size 2.8194 1.5748)
			(drill oval 2.4384 1.1938)
			(layers "*.Cu" "*.Mask")
			(remove_unused_layers no)
			(net "GND")
			(clearance 0.127)
			(thermal_gap 0.127)
		)
		(pad "G2" thru_hole oval
			(at 0 3.875024)
			(size 2.8194 1.5748)
			(drill oval 2.4384 1.1938)
			(layers "*.Cu" "*.Mask")
			(remove_unused_layers no)
			(net "GND")
			(clearance 0.127)
			(thermal_gap 0.127)
		)
		(pad "G3" thru_hole oval
			(at 0 68.97497)
			(size 2.8194 1.5748)
			(drill oval 2.4384 1.1938)
			(layers "*.Cu" "*.Mask")
			(remove_unused_layers no)
			(net "GND")
			(clearance 0.127)
			(thermal_gap 0.127)
		)
	)
)
